(kicad_pcb
	(version 20260206)
	(generator "pcbnew")
	(generator_version "10.0")
	(general
		(thickness 1.6)
		(legacy_teardrops no)
	)
	(paper "A4")
	(title_block
		(title "03242023_DA0F0TMBIJ0_F0T_Motherboard_J_brd_V01_OCP.brd")
		(comment 1 "Grand Teton / footprints 1348-1353 of 6105")
	)
	(layers
		(0 "F.Cu" signal "TOP")
		(4 "In1.Cu" signal "GND")
		(6 "In2.Cu" signal "IN1")
		(8 "In3.Cu" signal "GND1")
		(10 "In4.Cu" signal "IN2")
		(12 "In5.Cu" signal "GND2")
		(14 "In6.Cu" signal "IN3")
		(16 "In7.Cu" signal "GND3")
		(18 "In8.Cu" signal "VCC")
		(20 "In9.Cu" signal "VCC1")
		(22 "In10.Cu" signal "GND4")
		(24 "In11.Cu" signal "IN4")
		(26 "In12.Cu" signal "GND5")
		(28 "In13.Cu" signal "IN5")
		(30 "In14.Cu" signal "GND6")
		(32 "In15.Cu" signal "IN6")
		(34 "In16.Cu" signal "GND7")
		(2 "B.Cu" signal "BOTTOM")
		(9 "F.Adhes" user "F.Adhesive")
		(11 "B.Adhes" user "B.Adhesive")
		(13 "F.Paste" user "Package Geometry/Pastemask Top")
		(15 "B.Paste" user "Package Geometry/Pastemask Bottom")
		(5 "F.SilkS" user "Ref Des/Silkscreen Top")
		(7 "B.SilkS" user "Ref Des/Silkscreen Bottom")
		(1 "F.Mask" user "Board Geometry/Soldermask Top")
		(3 "B.Mask" user "Board Geometry/Soldermask Bottom")
		(17 "Dwgs.User" user "User.Drawings")
		(19 "Cmts.User" user "User.Comments")
		(21 "Eco1.User" user "User.Eco1")
		(23 "Eco2.User" user "User.Eco2")
		(25 "Edge.Cuts" user "Board Geometry/Outline")
		(27 "Margin" user)
		(31 "F.CrtYd" user "Package Geometry/Place Bound Top")
		(29 "B.CrtYd" user "Package Geometry/Place Bound Bottom")
		(35 "F.Fab" user "Ref Des/Assembly Top")
		(33 "B.Fab" user "Ref Des/Assembly Bottom")
	)
	(footprint ""
		(layer "F.Cu")
		(at 152.96388 -109.311948 90)
		(property "Reference" "U225"
			(at -2.224532 -4.60248 0)
			(unlocked yes)
			(layer "F.SilkS")
			(effects
				(font
					(size 0.7874 0.5842)
					(thickness 0.1524)
				)
				(justify left)
			)
		)
		(property "Value" ""
			(at 0 0 90)
			(layer "F.Fab")
			(effects
				(font
					(size 1.27 1.27)
				)
			)
		)
		(duplicate_pad_numbers_are_jumpers no)
		(fp_line
			(start 1.400048 -1.100074)
			(end -1.400048 -1.100074)
			(stroke
				(width 0.1524)
				(type default)
			)
			(layer "F.SilkS")
		)
		(fp_line
			(start 1.400048 -1.100074)
			(end 1.400048 1.100074)
			(stroke
				(width 0.1524)
				(type default)
			)
			(layer "F.SilkS")
		)
		(fp_line
			(start 1.400048 1.100074)
			(end -1.400048 1.100074)
			(stroke
				(width 0.1524)
				(type default)
			)
			(layer "F.SilkS")
		)
		(fp_line
			(start -1.400048 1.100074)
			(end -1.400048 -1.100074)
			(stroke
				(width 0.1524)
				(type default)
			)
			(layer "F.SilkS")
		)
		(fp_poly
			(pts
				(xy -0.960374 -1.217168) (xy -1.468374 -2.233168) (xy -0.452374 -2.233168)
			)
			(stroke
				(width 0)
				(type default)
			)
			(fill yes)
			(layer "F.SilkS")
		)
		(fp_line
			(start 0.674878 -1.100074)
			(end 0.674878 1.100074)
			(stroke
				(width 0.1)
				(type default)
			)
			(layer "F.Fab")
		)
		(fp_line
			(start -0.674878 -1.100074)
			(end 0.674878 -1.100074)
			(stroke
				(width 0.1)
				(type default)
			)
			(layer "F.Fab")
		)
		(fp_line
			(start 0.674878 1.100074)
			(end -0.674878 1.100074)
			(stroke
				(width 0.1)
				(type default)
			)
			(layer "F.Fab")
		)
		(fp_line
			(start -0.674878 1.100074)
			(end -0.674878 -1.100074)
			(stroke
				(width 0.1)
				(type default)
			)
			(layer "F.Fab")
		)
		(fp_poly
			(pts
				(xy -1.590548 -0.649986) (xy -2.606548 -1.157986) (xy -2.606548 -0.141986)
			)
			(stroke
				(width 0)
				(type default)
			)
			(fill yes)
			(layer "F.Fab")
		)
		(pad "1" smd rect
			(at -0.94996 -0.649986)
			(size 0.4318 0.6096)
			(layers "F.Cu" "F.Mask" "F.Paste")
			(net "OCP_V3_2_AUX_PWR_EN_R3")
		)
		(pad "2" smd rect
			(at -0.94996 0)
			(size 0.4318 0.6096)
			(layers "F.Cu" "F.Mask" "F.Paste")
			(net "RST_SMB_SWITCH_N")
		)
		(pad "3" smd rect
			(at -0.94996 0.649986)
			(size 0.4318 0.6096)
			(layers "F.Cu" "F.Mask" "F.Paste")
			(net "GND")
		)
		(pad "4" smd rect
			(at 0.94996 0.649986)
			(size 0.4318 0.6096)
			(layers "F.Cu" "F.Mask" "F.Paste")
			(net "RST_HP_OCP_V3_2_R_N")
		)
		(pad "5" smd rect
			(at 0.94996 -0.649986)
			(size 0.4318 0.6096)
			(layers "F.Cu" "F.Mask" "F.Paste")
			(net "P3V3_AUX")
		)
	)
	(footprint ""
		(layer "F.Cu")
		(at 400.558 -177.206148)
		(property "Reference" "PC1574"
			(at 0 0 0)
			(layer "F.SilkS")
			(hide yes)
			(effects
				(font
					(size 1.27 1.27)
				)
			)
		)
		(property "Value" ""
			(at 0 0 0)
			(layer "F.Fab")
			(effects
				(font
					(size 1.27 1.27)
				)
			)
		)
		(duplicate_pad_numbers_are_jumpers no)
		(fp_line
			(start 2.750058 0.999998)
			(end -2.750058 0.999998)
			(stroke
				(width 0.1524)
				(type default)
			)
			(layer "F.SilkS")
		)
		(fp_circle
			(center 0 0.999998)
			(end 2.750058 0.999998)
			(stroke
				(width 0.1524)
				(type default)
			)
			(fill no)
			(layer "F.SilkS")
		)
		(fp_poly
			(pts
				(arc
					(start 2.750058 0.999998)
					(mid 0 3.750056)
					(end -2.750058 0.999998)
				)
			)
			(stroke
				(width 0)
				(type default)
			)
			(fill yes)
			(layer "F.SilkS")
		)
		(fp_circle
			(center 0 0.999998)
			(end 2.750058 0.999998)
			(stroke
				(width 0.1)
				(type default)
			)
			(fill no)
			(layer "F.Fab")
		)
		(pad "1" thru_hole rect
			(at 0 0)
			(size 1.5748 1.5748)
			(drill 1.0668)
			(layers "*.Cu" "*.Mask")
			(remove_unused_layers no)
			(net "PVCCINFAON_CPU0")
			(clearance 0)
			(padstack
				(mode front_inner_back)
				(layer "Inner"
					(shape circle)
					(size 1.5748 1.5748)
					(clearance 0)
				)
				(layer "B.Cu"
					(shape rect)
					(size 1.5748 1.5748)
					(clearance 0)
				)
			)
		)
		(pad "2" thru_hole circle
			(at 0 1.999996)
			(size 1.5748 1.5748)
			(drill 1.0668)
			(layers "*.Cu" "*.Mask")
			(remove_unused_layers no)
			(net "GND")
			(clearance 0)
		)
	)
	(footprint ""
		(layer "F.Cu")
		(at 134.54888 -100.167948 90)
		(property "Reference" "R4412"
			(at 0 0 90)
			(layer "F.SilkS")
			(hide yes)
			(effects
				(font
					(size 1.27 1.27)
				)
			)
		)
		(property "Value" ""
			(at 0 0 90)
			(layer "F.Fab")
			(effects
				(font
					(size 1.27 1.27)
				)
			)
		)
		(duplicate_pad_numbers_are_jumpers no)
		(fp_line
			(start 0.7874 -0.4064)
			(end 0.7874 0.4064)
			(stroke
				(width 0.1524)
				(type default)
			)
			(layer "F.SilkS")
		)
		(fp_line
			(start -0.7874 -0.4064)
			(end 0.7874 -0.4064)
			(stroke
				(width 0.1524)
				(type default)
			)
			(layer "F.SilkS")
		)
		(fp_line
			(start 0.7874 0.4064)
			(end -0.7874 0.4064)
			(stroke
				(width 0.1524)
				(type default)
			)
			(layer "F.SilkS")
		)
		(fp_line
			(start -0.7874 0.4064)
			(end -0.7874 -0.4064)
			(stroke
				(width 0.1524)
				(type default)
			)
			(layer "F.SilkS")
		)
		(fp_line
			(start -0.12065 -0.305054)
			(end -0.12065 -0.2794)
			(stroke
				(width 0.1)
				(type default)
			)
			(layer "F.Fab")
		)
		(fp_line
			(start -0.67945 -0.305054)
			(end -0.12065 -0.305054)
			(stroke
				(width 0.1)
				(type default)
			)
			(layer "F.Fab")
		)
		(fp_line
			(start 0.67945 -0.3048)
			(end 0.67945 0.3048)
			(stroke
				(width 0.1)
				(type default)
			)
			(layer "F.Fab")
		)
		(fp_line
			(start 0.12065 -0.3048)
			(end 0.67945 -0.3048)
			(stroke
				(width 0.1)
				(type default)
			)
			(layer "F.Fab")
		)
		(fp_line
			(start 0.12065 -0.2794)
			(end 0.12065 -0.3048)
			(stroke
				(width 0.1)
				(type default)
			)
			(layer "F.Fab")
		)
		(fp_line
			(start -0.12065 -0.2794)
			(end 0.12065 -0.2794)
			(stroke
				(width 0.1)
				(type default)
			)
			(layer "F.Fab")
		)
		(fp_line
			(start 0.120396 0.2794)
			(end -0.12065 0.2794)
			(stroke
				(width 0.1)
				(type default)
			)
			(layer "F.Fab")
		)
		(fp_line
			(start -0.12065 0.2794)
			(end -0.12065 0.3048)
			(stroke
				(width 0.1)
				(type default)
			)
			(layer "F.Fab")
		)
		(fp_line
			(start 0.67945 0.3048)
			(end 0.120396 0.3048)
			(stroke
				(width 0.1)
				(type default)
			)
			(layer "F.Fab")
		)
		(fp_line
			(start 0.120396 0.3048)
			(end 0.120396 0.2794)
			(stroke
				(width 0.1)
				(type default)
			)
			(layer "F.Fab")
		)
		(fp_line
			(start -0.12065 0.3048)
			(end -0.67945 0.3048)
			(stroke
				(width 0.1)
				(type default)
			)
			(layer "F.Fab")
		)
		(fp_line
			(start -0.67945 0.3048)
			(end -0.67945 -0.305054)
			(stroke
				(width 0.1)
				(type default)
			)
			(layer "F.Fab")
		)
		(pad "1" smd circle
			(at -0.40005 0 90)
			(size 0 0)
			(layers "F.Cu" "F.Mask" "F.Paste")
			(net "P3V3")
		)
		(pad "2" smd circle
			(at 0.40005 0 90)
			(size 0 0)
			(layers "F.Cu" "F.Mask" "F.Paste")
			(net "H_CPU1_MEMTRIP_VT_N")
		)
	)
	(footprint ""
		(layer "F.Cu")
		(at 440.592972 -22.551898 180)
		(property "Reference" "PR3838"
			(at 0 0 180)
			(layer "F.SilkS")
			(hide yes)
			(effects
				(font
					(size 1.27 1.27)
				)
			)
		)
		(property "Value" ""
			(at 0 0 180)
			(layer "F.Fab")
			(effects
				(font
					(size 1.27 1.27)
				)
			)
		)
		(duplicate_pad_numbers_are_jumpers no)
		(fp_line
			(start 0.7874 0.4064)
			(end -0.7874 0.4064)
			(stroke
				(width 0.1524)
				(type default)
			)
			(layer "F.SilkS")
		)
		(fp_line
			(start 0.7874 -0.4064)
			(end 0.7874 0.4064)
			(stroke
				(width 0.1524)
				(type default)
			)
			(layer "F.SilkS")
		)
		(fp_line
			(start -0.7874 0.4064)
			(end -0.7874 -0.4064)
			(stroke
				(width 0.1524)
				(type default)
			)
			(layer "F.SilkS")
		)
		(fp_line
			(start -0.7874 -0.4064)
			(end 0.7874 -0.4064)
			(stroke
				(width 0.1524)
				(type default)
			)
			(layer "F.SilkS")
		)
		(fp_line
			(start 0.67945 0.3048)
			(end 0.120396 0.3048)
			(stroke
				(width 0.1)
				(type default)
			)
			(layer "F.Fab")
		)
		(fp_line
			(start 0.67945 -0.3048)
			(end 0.67945 0.3048)
			(stroke
				(width 0.1)
				(type default)
			)
			(layer "F.Fab")
		)
		(fp_line
			(start 0.12065 -0.2794)
			(end 0.12065 -0.3048)
			(stroke
				(width 0.1)
				(type default)
			)
			(layer "F.Fab")
		)
		(fp_line
			(start 0.12065 -0.3048)
			(end 0.67945 -0.3048)
			(stroke
				(width 0.1)
				(type default)
			)
			(layer "F.Fab")
		)
		(fp_line
			(start 0.120396 0.3048)
			(end 0.120396 0.2794)
			(stroke
				(width 0.1)
				(type default)
			)
			(layer "F.Fab")
		)
		(fp_line
			(start 0.120396 0.2794)
			(end -0.12065 0.2794)
			(stroke
				(width 0.1)
				(type default)
			)
			(layer "F.Fab")
		)
		(fp_line
			(start -0.12065 0.3048)
			(end -0.67945 0.3048)
			(stroke
				(width 0.1)
				(type default)
			)
			(layer "F.Fab")
		)
		(fp_line
			(start -0.12065 0.2794)
			(end -0.12065 0.3048)
			(stroke
				(width 0.1)
				(type default)
			)
			(layer "F.Fab")
		)
		(fp_line
			(start -0.12065 -0.2794)
			(end 0.12065 -0.2794)
			(stroke
				(width 0.1)
				(type default)
			)
			(layer "F.Fab")
		)
		(fp_line
			(start -0.12065 -0.305054)
			(end -0.12065 -0.2794)
			(stroke
				(width 0.1)
				(type default)
			)
			(layer "F.Fab")
		)
		(fp_line
			(start -0.67945 0.3048)
			(end -0.67945 -0.305054)
			(stroke
				(width 0.1)
				(type default)
			)
			(layer "F.Fab")
		)
		(fp_line
			(start -0.67945 -0.305054)
			(end -0.12065 -0.305054)
			(stroke
				(width 0.1)
				(type default)
			)
			(layer "F.Fab")
		)
		(pad "1" smd circle
			(at -0.40005 0 180)
			(size 0 0)
			(layers "F.Cu" "F.Mask" "F.Paste")
			(net "P12V_OCP_SFF")
		)
		(pad "2" smd circle
			(at 0.40005 0 180)
			(size 0 0)
			(layers "F.Cu" "F.Mask" "F.Paste")
			(net "P12V_OCP_AVIN_PD_1")
		)
	)
	(footprint ""
		(layer "F.Cu")
		(at 329.60691 -20.616926)
		(property "Reference" "R1268"
			(at 0 0 0)
			(layer "F.SilkS")
			(hide yes)
			(effects
				(font
					(size 1.27 1.27)
				)
			)
		)
		(property "Value" ""
			(at 0 0 0)
			(layer "F.Fab")
			(effects
				(font
					(size 1.27 1.27)
				)
			)
		)
		(duplicate_pad_numbers_are_jumpers no)
		(fp_line
			(start -0.7874 -0.4064)
			(end 0.7874 -0.4064)
			(stroke
				(width 0.1524)
				(type default)
			)
			(layer "F.SilkS")
		)
		(fp_line
			(start -0.7874 0.4064)
			(end -0.7874 -0.4064)
			(stroke
				(width 0.1524)
				(type default)
			)
			(layer "F.SilkS")
		)
		(fp_line
			(start 0.7874 -0.4064)
			(end 0.7874 0.4064)
			(stroke
				(width 0.1524)
				(type default)
			)
			(layer "F.SilkS")
		)
		(fp_line
			(start 0.7874 0.4064)
			(end -0.7874 0.4064)
			(stroke
				(width 0.1524)
				(type default)
			)
			(layer "F.SilkS")
		)
		(fp_line
			(start -0.67945 -0.305054)
			(end -0.12065 -0.305054)
			(stroke
				(width 0.1)
				(type default)
			)
			(layer "F.Fab")
		)
		(fp_line
			(start -0.67945 0.3048)
			(end -0.67945 -0.305054)
			(stroke
				(width 0.1)
				(type default)
			)
			(layer "F.Fab")
		)
		(fp_line
			(start -0.12065 -0.305054)
			(end -0.12065 -0.2794)
			(stroke
				(width 0.1)
				(type default)
			)
			(layer "F.Fab")
		)
		(fp_line
			(start -0.12065 -0.2794)
			(end 0.12065 -0.2794)
			(stroke
				(width 0.1)
				(type default)
			)
			(layer "F.Fab")
		)
		(fp_line
			(start -0.12065 0.2794)
			(end -0.12065 0.3048)
			(stroke
				(width 0.1)
				(type default)
			)
			(layer "F.Fab")
		)
		(fp_line
			(start -0.12065 0.3048)
			(end -0.67945 0.3048)
			(stroke
				(width 0.1)
				(type default)
			)
			(layer "F.Fab")
		)
		(fp_line
			(start 0.120396 0.2794)
			(end -0.12065 0.2794)
			(stroke
				(width 0.1)
				(type default)
			)
			(layer "F.Fab")
		)
		(fp_line
			(start 0.120396 0.3048)
			(end 0.120396 0.2794)
			(stroke
				(width 0.1)
				(type default)
			)
			(layer "F.Fab")
		)
		(fp_line
			(start 0.12065 -0.3048)
			(end 0.67945 -0.3048)
			(stroke
				(width 0.1)
				(type default)
			)
			(layer "F.Fab")
		)
		(fp_line
			(start 0.12065 -0.2794)
			(end 0.12065 -0.3048)
			(stroke
				(width 0.1)
				(type default)
			)
			(layer "F.Fab")
		)
		(fp_line
			(start 0.67945 -0.3048)
			(end 0.67945 0.3048)
			(stroke
				(width 0.1)
				(type default)
			)
			(layer "F.Fab")
		)
		(fp_line
			(start 0.67945 0.3048)
			(end 0.120396 0.3048)
			(stroke
				(width 0.1)
				(type default)
			)
			(layer "F.Fab")
		)
		(pad "1" smd circle
			(at -0.40005 0)
			(size 0 0)
			(layers "F.Cu" "F.Mask" "F.Paste")
			(net "IRQ_BMC_PCH_NMI_R")
		)
		(pad "2" smd circle
			(at 0.40005 0)
			(size 0 0)
			(layers "F.Cu" "F.Mask" "F.Paste")
			(net "IRQ_BMC_PCH_NMI")
		)
	)
	(footprint ""
		(layer "F.Cu")
		(at 112.027462 -338.86013)
		(property "Reference" "PR298"
			(at 0 0 0)
			(layer "F.SilkS")
			(hide yes)
			(effects
				(font
					(size 1.27 1.27)
				)
			)
		)
		(property "Value" ""
			(at 0 0 0)
			(layer "F.Fab")
			(effects
				(font
					(size 1.27 1.27)
				)
			)
		)
		(duplicate_pad_numbers_are_jumpers no)
		(fp_line
			(start -0.7874 -0.4064)
			(end 0.7874 -0.4064)
			(stroke
				(width 0.1524)
				(type default)
			)
			(layer "F.SilkS")
		)
		(fp_line
			(start -0.7874 0.4064)
			(end -0.7874 -0.4064)
			(stroke
				(width 0.1524)
				(type default)
			)
			(layer "F.SilkS")
		)
		(fp_line
			(start 0.7874 -0.4064)
			(end 0.7874 0.4064)
			(stroke
				(width 0.1524)
				(type default)
			)
			(layer "F.SilkS")
		)
		(fp_line
			(start 0.7874 0.4064)
			(end -0.7874 0.4064)
			(stroke
				(width 0.1524)
				(type default)
			)
			(layer "F.SilkS")
		)
		(fp_line
			(start -0.67945 -0.305054)
			(end -0.12065 -0.305054)
			(stroke
				(width 0.1)
				(type default)
			)
			(layer "F.Fab")
		)
		(fp_line
			(start -0.67945 0.3048)
			(end -0.67945 -0.305054)
			(stroke
				(width 0.1)
				(type default)
			)
			(layer "F.Fab")
		)
		(fp_line
			(start -0.12065 -0.305054)
			(end -0.12065 -0.2794)
			(stroke
				(width 0.1)
				(type default)
			)
			(layer "F.Fab")
		)
		(fp_line
			(start -0.12065 -0.2794)
			(end 0.12065 -0.2794)
			(stroke
				(width 0.1)
				(type default)
			)
			(layer "F.Fab")
		)
		(fp_line
			(start -0.12065 0.2794)
			(end -0.12065 0.3048)
			(stroke
				(width 0.1)
				(type default)
			)
			(layer "F.Fab")
		)
		(fp_line
			(start -0.12065 0.3048)
			(end -0.67945 0.3048)
			(stroke
				(width 0.1)
				(type default)
			)
			(layer "F.Fab")
		)
		(fp_line
			(start 0.120396 0.2794)
			(end -0.12065 0.2794)
			(stroke
				(width 0.1)
				(type default)
			)
			(layer "F.Fab")
		)
		(fp_line
			(start 0.120396 0.3048)
			(end 0.120396 0.2794)
			(stroke
				(width 0.1)
				(type default)
			)
			(layer "F.Fab")
		)
		(fp_line
			(start 0.12065 -0.3048)
			(end 0.67945 -0.3048)
			(stroke
				(width 0.1)
				(type default)
			)
			(layer "F.Fab")
		)
		(fp_line
			(start 0.12065 -0.2794)
			(end 0.12065 -0.3048)
			(stroke
				(width 0.1)
				(type default)
			)
			(layer "F.Fab")
		)
		(fp_line
			(start 0.67945 -0.3048)
			(end 0.67945 0.3048)
			(stroke
				(width 0.1)
				(type default)
			)
			(layer "F.Fab")
		)
		(fp_line
			(start 0.67945 0.3048)
			(end 0.120396 0.3048)
			(stroke
				(width 0.1)
				(type default)
			)
			(layer "F.Fab")
		)
		(pad "1" smd circle
			(at -0.40005 0)
			(size 0 0)
			(layers "F.Cu" "F.Mask" "F.Paste")
			(net "PVCCIN_CPU1_LSET3")
		)
		(pad "2" smd circle
			(at 0.40005 0)
			(size 0 0)
			(layers "F.Cu" "F.Mask" "F.Paste")
			(net "GND")
		)
	)
)
